(kicad_pcb
	(version 20260206)
	(generator "pcbnew")
	(generator_version "10.0")
	(general
		(thickness 1.6)
		(legacy_teardrops no)
	)
	(paper "A4")
	(title_block
		(title "Bryce Canyon_SCC_16316-1_OCP.brd")
		(comment 1 "Bryce Canyon / footprints 1205-1212 of 1561")
	)
	(layers
		(0 "F.Cu" signal "TOP")
		(4 "In1.Cu" signal "L2GND")
		(6 "In2.Cu" signal "L3")
		(8 "In3.Cu" signal "L4VCC")
		(10 "In4.Cu" signal "L5VCC")
		(12 "In5.Cu" signal "L6")
		(14 "In6.Cu" signal "L7GND")
		(2 "B.Cu" signal "BOTTOM")
		(9 "F.Adhes" user "F.Adhesive")
		(11 "B.Adhes" user "B.Adhesive")
		(13 "F.Paste" user "Package Geometry/Pastemask Top")
		(15 "B.Paste" user "Package Geometry/Pastemask Bottom")
		(5 "F.SilkS" user "Ref Des/Silkscreen Top")
		(7 "B.SilkS" user "Ref Des/Silkscreen Bottom")
		(1 "F.Mask" user "Board Geometry/Soldermask Top")
		(3 "B.Mask" user "Board Geometry/Soldermask Bottom")
		(17 "Dwgs.User" user "User.Drawings")
		(19 "Cmts.User" user "User.Comments")
		(21 "Eco1.User" user "User.Eco1")
		(23 "Eco2.User" user "User.Eco2")
		(25 "Edge.Cuts" user "Board Geometry/Outline")
		(27 "Margin" user)
		(31 "F.CrtYd" user "Package Geometry/Place Bound Top")
		(29 "B.CrtYd" user "Package Geometry/Place Bound Bottom")
		(35 "F.Fab" user "Ref Des/Assembly Top")
		(33 "B.Fab" user "Ref Des/Assembly Bottom")
	)
	(footprint ""
		(layer "B.Cu")
		(at 117.348 -66.3575)
		(property "Reference" "C158"
			(at 0 0 0)
			(layer "B.SilkS")
			(hide yes)
			(effects
				(font
					(size 1.27 1.27)
				)
				(justify mirror)
			)
		)
		(property "Value" "SCD1U6D3V1KX-GP"
			(at 2.8321 -1.7399 0)
			(unlocked yes)
			(layer "B.Fab")
			(hide yes)
			(effects
				(font
					(size 1.016 1.016)
					(thickness 0.1524)
				)
				(justify mirror)
			)
		)
		(property "Device Type" "C0201H13"
			(at 2.8321 -3.2639 0)
			(unlocked yes)
			(layer "B.Fab")
			(hide yes)
			(effects
				(font
					(size 1.016 1.016)
					(thickness 0.1524)
				)
				(justify mirror)
			)
		)
		(duplicate_pad_numbers_are_jumpers no)
		(fp_rect
			(start 0.2794 0.6477)
			(end -0.2794 -0.6477)
			(stroke
				(width 0)
				(type default)
			)
			(fill no)
			(layer "B.CrtYd")
		)
		(fp_rect
			(start 0.2794 0.6477)
			(end -0.2794 -0.6477)
			(stroke
				(width 0)
				(type default)
			)
			(fill no)
			(layer "B.Fab")
		)
		(pad "1" smd custom
			(at 0 -0.2794 180)
			(size 0.0762 0.0762)
			(layers "B.Cu" "B.Mask" "B.Paste")
			(net "P0V9")
			(options
				(clearance outline)
				(anchor circle)
			)
			(primitives
				(gr_poly
					(pts
						(arc
							(start 0.1524 0.127)
							(mid 0.137521 0.162921)
							(end 0.1016 0.1778)
						)
						(arc
							(start -0.1016 0.1778)
							(mid -0.137521 0.162921)
							(end -0.1524 0.127)
						)
						(arc
							(start -0.1524 -0.127)
							(mid -0.137521 -0.162921)
							(end -0.1016 -0.1778)
						)
						(arc
							(start 0.1016 -0.1778)
							(mid 0.137521 -0.162921)
							(end 0.1524 -0.127)
						)
					)
					(width 0)
					(fill yes)
				)
			)
		)
		(pad "2" smd custom
			(at 0 0.2794 180)
			(size 0.0762 0.0762)
			(layers "B.Cu" "B.Mask" "B.Paste")
			(net "GND")
			(options
				(clearance outline)
				(anchor circle)
			)
			(primitives
				(gr_poly
					(pts
						(arc
							(start 0.1524 0.127)
							(mid 0.137521 0.162921)
							(end 0.1016 0.1778)
						)
						(arc
							(start -0.1016 0.1778)
							(mid -0.137521 0.162921)
							(end -0.1524 0.127)
						)
						(arc
							(start -0.1524 -0.127)
							(mid -0.137521 -0.162921)
							(end -0.1016 -0.1778)
						)
						(arc
							(start 0.1016 -0.1778)
							(mid 0.137521 -0.162921)
							(end 0.1524 -0.127)
						)
					)
					(width 0)
					(fill yes)
				)
			)
		)
	)
	(footprint ""
		(layer "B.Cu")
		(at 186.383168 -44.545504 -90)
		(property "Reference" "TP109"
			(at 0 0 90)
			(layer "B.SilkS")
			(hide yes)
			(effects
				(font
					(size 1.27 1.27)
				)
				(justify mirror)
			)
		)
		(property "Value" "TPAD28-2-GP"
			(at 0.0127 -1.6637 270)
			(unlocked yes)
			(layer "B.Fab")
			(hide yes)
			(effects
				(font
					(size 1.016 1.016)
					(thickness 0.1524)
				)
				(justify mirror)
			)
		)
		(property "Device Type" "TPAD28"
			(at 0.0127 -3.1877 270)
			(unlocked yes)
			(layer "B.Fab")
			(hide yes)
			(effects
				(font
					(size 1.016 1.016)
					(thickness 0.1524)
				)
				(justify mirror)
			)
		)
		(duplicate_pad_numbers_are_jumpers no)
		(fp_poly
			(pts
				(arc
					(start 0 -0.3556)
					(mid 0 0.3556)
					(end 0 -0.3556)
				)
			)
			(stroke
				(width 0)
				(type default)
			)
			(fill no)
			(layer "B.CrtYd")
		)
		(fp_poly
			(pts
				(arc
					(start 0 -0.6096)
					(mid 0 0.6096)
					(end 0 -0.6096)
				)
			)
			(stroke
				(width 0)
				(type default)
			)
			(fill no)
			(layer "B.Fab")
		)
		(pad "1" smd circle
			(at 0 0 90)
			(size 0.7112 0.7112)
			(layers "B.Cu" "B.Mask" "B.Paste")
			(net "XM_ADDR_24")
		)
	)
	(footprint ""
		(layer "B.Cu")
		(at 108.5342 -65.5066 -90)
		(property "Reference" "C126"
			(at 0 0 90)
			(layer "B.SilkS")
			(hide yes)
			(effects
				(font
					(size 1.27 1.27)
				)
				(justify mirror)
			)
		)
		(property "Value" "SC1KP25V1KX-GP"
			(at 2.8321 -1.7399 270)
			(unlocked yes)
			(layer "B.Fab")
			(hide yes)
			(effects
				(font
					(size 1.016 1.016)
					(thickness 0.1524)
				)
				(justify mirror)
			)
		)
		(property "Device Type" "C0201H13"
			(at 2.8321 -3.2639 270)
			(unlocked yes)
			(layer "B.Fab")
			(hide yes)
			(effects
				(font
					(size 1.016 1.016)
					(thickness 0.1524)
				)
				(justify mirror)
			)
		)
		(duplicate_pad_numbers_are_jumpers no)
		(fp_rect
			(start 0.2794 0.6477)
			(end -0.2794 -0.6477)
			(stroke
				(width 0)
				(type default)
			)
			(fill no)
			(layer "B.CrtYd")
		)
		(fp_rect
			(start 0.2794 0.6477)
			(end -0.2794 -0.6477)
			(stroke
				(width 0)
				(type default)
			)
			(fill no)
			(layer "B.Fab")
		)
		(pad "1" smd custom
			(at 0 -0.2794 90)
			(size 0.0762 0.0762)
			(layers "B.Cu" "B.Mask" "B.Paste")
			(net "P1V8_E")
			(options
				(clearance outline)
				(anchor circle)
			)
			(primitives
				(gr_poly
					(pts
						(arc
							(start 0.1524 0.127)
							(mid 0.137521 0.162921)
							(end 0.1016 0.1778)
						)
						(arc
							(start -0.1016 0.1778)
							(mid -0.137521 0.162921)
							(end -0.1524 0.127)
						)
						(arc
							(start -0.1524 -0.127)
							(mid -0.137521 -0.162921)
							(end -0.1016 -0.1778)
						)
						(arc
							(start 0.1016 -0.1778)
							(mid 0.137521 -0.162921)
							(end 0.1524 -0.127)
						)
					)
					(width 0)
					(fill yes)
				)
			)
		)
		(pad "2" smd custom
			(at 0 0.2794 90)
			(size 0.0762 0.0762)
			(layers "B.Cu" "B.Mask" "B.Paste")
			(net "GND")
			(options
				(clearance outline)
				(anchor circle)
			)
			(primitives
				(gr_poly
					(pts
						(arc
							(start 0.1524 0.127)
							(mid 0.137521 0.162921)
							(end 0.1016 0.1778)
						)
						(arc
							(start -0.1016 0.1778)
							(mid -0.137521 0.162921)
							(end -0.1524 0.127)
						)
						(arc
							(start -0.1524 -0.127)
							(mid -0.137521 -0.162921)
							(end -0.1016 -0.1778)
						)
						(arc
							(start 0.1016 -0.1778)
							(mid 0.137521 -0.162921)
							(end 0.1524 -0.127)
						)
					)
					(width 0)
					(fill yes)
				)
			)
		)
	)
	(footprint ""
		(layer "B.Cu")
		(at 100.2538 -44.2214 180)
		(property "Reference" "C83"
			(at 0 0 0)
			(layer "B.SilkS")
			(hide yes)
			(effects
				(font
					(size 1.27 1.27)
				)
				(justify mirror)
			)
		)
		(property "Value" "SCD01U16V1KX-GP"
			(at 2.8321 -1.7399 180)
			(unlocked yes)
			(layer "B.Fab")
			(hide yes)
			(effects
				(font
					(size 1.016 1.016)
					(thickness 0.1524)
				)
				(justify mirror)
			)
		)
		(property "Device Type" "C0201H13"
			(at 2.8321 -3.2639 180)
			(unlocked yes)
			(layer "B.Fab")
			(hide yes)
			(effects
				(font
					(size 1.016 1.016)
					(thickness 0.1524)
				)
				(justify mirror)
			)
		)
		(duplicate_pad_numbers_are_jumpers no)
		(fp_rect
			(start 0.2794 0.6477)
			(end -0.2794 -0.6477)
			(stroke
				(width 0)
				(type default)
			)
			(fill no)
			(layer "B.CrtYd")
		)
		(fp_rect
			(start 0.2794 0.6477)
			(end -0.2794 -0.6477)
			(stroke
				(width 0)
				(type default)
			)
			(fill no)
			(layer "B.Fab")
		)
		(pad "1" smd custom
			(at 0 -0.2794)
			(size 0.0762 0.0762)
			(layers "B.Cu" "B.Mask" "B.Paste")
			(net "PHY_DPB_TO_SCC_18_DP")
			(options
				(clearance outline)
				(anchor circle)
			)
			(primitives
				(gr_poly
					(pts
						(arc
							(start 0.1524 0.127)
							(mid 0.137521 0.162921)
							(end 0.1016 0.1778)
						)
						(arc
							(start -0.1016 0.1778)
							(mid -0.137521 0.162921)
							(end -0.1524 0.127)
						)
						(arc
							(start -0.1524 -0.127)
							(mid -0.137521 -0.162921)
							(end -0.1016 -0.1778)
						)
						(arc
							(start 0.1016 -0.1778)
							(mid 0.137521 -0.162921)
							(end 0.1524 -0.127)
						)
					)
					(width 0)
					(fill yes)
				)
			)
		)
		(pad "2" smd custom
			(at 0 0.2794)
			(size 0.0762 0.0762)
			(layers "B.Cu" "B.Mask" "B.Paste")
			(net "PHY_DPB_TO_SCC_C_18_DP")
			(options
				(clearance outline)
				(anchor circle)
			)
			(primitives
				(gr_poly
					(pts
						(arc
							(start 0.1524 0.127)
							(mid 0.137521 0.162921)
							(end 0.1016 0.1778)
						)
						(arc
							(start -0.1016 0.1778)
							(mid -0.137521 0.162921)
							(end -0.1524 0.127)
						)
						(arc
							(start -0.1524 -0.127)
							(mid -0.137521 -0.162921)
							(end -0.1016 -0.1778)
						)
						(arc
							(start 0.1016 -0.1778)
							(mid 0.137521 -0.162921)
							(end 0.1524 -0.127)
						)
					)
					(width 0)
					(fill yes)
				)
			)
		)
	)
	(footprint ""
		(layer "B.Cu")
		(at 198.511414 -46.439074 -90)
		(property "Reference" "R205"
			(at 0 0 90)
			(layer "B.SilkS")
			(hide yes)
			(effects
				(font
					(size 1.27 1.27)
				)
				(justify mirror)
			)
		)
		(property "Value" "0R2J-2-GP"
			(at -0.064008 -3.993896 270)
			(unlocked yes)
			(layer "B.Fab")
			(hide yes)
			(effects
				(font
					(size 1.016 1.016)
					(thickness 0.1524)
				)
				(justify mirror)
			)
		)
		(property "Device Type" "R402H16"
			(at -0.064008 -5.517896 270)
			(unlocked yes)
			(layer "B.Fab")
			(hide yes)
			(effects
				(font
					(size 1.016 1.016)
					(thickness 0.1524)
				)
				(justify mirror)
			)
		)
		(duplicate_pad_numbers_are_jumpers no)
		(fp_line
			(start -0.508 -0.9398)
			(end 0.508 -0.9398)
			(stroke
				(width 0.1524)
				(type default)
			)
			(layer "B.SilkS")
		)
		(fp_line
			(start 0.508 -0.9398)
			(end 0.508 0.9398)
			(stroke
				(width 0.1524)
				(type default)
			)
			(layer "B.SilkS")
		)
		(fp_rect
			(start 0.508 0.9398)
			(end -0.508 -0.9398)
			(stroke
				(width 0)
				(type default)
			)
			(fill no)
			(layer "B.CrtYd")
		)
		(fp_rect
			(start 0.508 0.9398)
			(end -0.508 -0.9398)
			(stroke
				(width 0)
				(type default)
			)
			(fill no)
			(layer "B.Fab")
		)
		(pad "1" smd custom
			(at 0 -0.4445 90)
			(size 0.1397 0.1397)
			(layers "B.Cu" "B.Mask" "B.Paste")
			(net "IOC_EEPROM_SDA")
			(options
				(clearance outline)
				(anchor circle)
			)
			(primitives
				(gr_poly
					(pts
						(arc
							(start -0.1778 0.2794)
							(mid -0.249642 0.249642)
							(end -0.2794 0.1778)
						)
						(arc
							(start -0.2794 -0.1778)
							(mid -0.249642 -0.249642)
							(end -0.1778 -0.2794)
						)
						(arc
							(start 0.1778 -0.2794)
							(mid 0.249642 -0.249642)
							(end 0.2794 -0.1778)
						)
						(arc
							(start 0.2794 0.1778)
							(mid 0.249642 0.249642)
							(end 0.1778 0.2794)
						)
					)
					(width 0)
					(fill yes)
				)
			)
		)
		(pad "2" smd custom
			(at 0 0.4445 90)
			(size 0.1397 0.1397)
			(layers "B.Cu" "B.Mask" "B.Paste")
			(net "SBL_SDA")
			(options
				(clearance outline)
				(anchor circle)
			)
			(primitives
				(gr_poly
					(pts
						(arc
							(start -0.1778 0.2794)
							(mid -0.249642 0.249642)
							(end -0.2794 0.1778)
						)
						(arc
							(start -0.2794 -0.1778)
							(mid -0.249642 -0.249642)
							(end -0.1778 -0.2794)
						)
						(arc
							(start 0.1778 -0.2794)
							(mid 0.249642 -0.249642)
							(end 0.2794 -0.1778)
						)
						(arc
							(start 0.2794 0.1778)
							(mid 0.249642 0.249642)
							(end 0.1778 0.2794)
						)
					)
					(width 0)
					(fill yes)
				)
			)
		)
	)
	(footprint ""
		(layer "B.Cu")
		(at 165.670992 -11.70813)
		(property "Reference" "C509"
			(at 0 0 0)
			(layer "B.SilkS")
			(hide yes)
			(effects
				(font
					(size 1.27 1.27)
				)
				(justify mirror)
			)
		)
		(property "Value" "SCD1U16V2KX-3GP"
			(at -1.1811 -2.7051 0)
			(unlocked yes)
			(layer "B.Fab")
			(hide yes)
			(effects
				(font
					(size 1.016 1.016)
					(thickness 0.1524)
				)
				(justify mirror)
			)
		)
		(property "Device Type" "C402H22"
			(at -1.1811 -4.2291 0)
			(unlocked yes)
			(layer "B.Fab")
			(hide yes)
			(effects
				(font
					(size 1.016 1.016)
					(thickness 0.1524)
				)
				(justify mirror)
			)
		)
		(duplicate_pad_numbers_are_jumpers no)
		(fp_rect
			(start 0.4318 0.9525)
			(end -0.4318 -0.9525)
			(stroke
				(width 0)
				(type default)
			)
			(fill no)
			(layer "B.CrtYd")
		)
		(fp_rect
			(start 0.4318 0.9525)
			(end -0.4318 -0.9525)
			(stroke
				(width 0)
				(type default)
			)
			(fill no)
			(layer "B.Fab")
		)
		(pad "1" smd custom
			(at 0 -0.4445 180)
			(size 0.1524 0.1524)
			(layers "B.Cu" "B.Mask" "B.Paste")
			(net "P3V3")
			(options
				(clearance outline)
				(anchor circle)
			)
			(primitives
				(gr_poly
					(pts
						(arc
							(start 0.3048 0.2032)
							(mid 0.275042 0.275042)
							(end 0.2032 0.3048)
						)
						(arc
							(start -0.2032 0.3048)
							(mid -0.275042 0.275042)
							(end -0.3048 0.2032)
						)
						(arc
							(start -0.3048 -0.2032)
							(mid -0.275042 -0.275042)
							(end -0.2032 -0.3048)
						)
						(arc
							(start 0.2032 -0.3048)
							(mid 0.275042 -0.275042)
							(end 0.3048 -0.2032)
						)
					)
					(width 0)
					(fill yes)
				)
			)
		)
		(pad "2" smd custom
			(at 0 0.4445 180)
			(size 0.1524 0.1524)
			(layers "B.Cu" "B.Mask" "B.Paste")
			(net "GND")
			(options
				(clearance outline)
				(anchor circle)
			)
			(primitives
				(gr_poly
					(pts
						(arc
							(start 0.3048 0.2032)
							(mid 0.275042 0.275042)
							(end 0.2032 0.3048)
						)
						(arc
							(start -0.2032 0.3048)
							(mid -0.275042 0.275042)
							(end -0.3048 0.2032)
						)
						(arc
							(start -0.3048 -0.2032)
							(mid -0.275042 -0.275042)
							(end -0.2032 -0.3048)
						)
						(arc
							(start 0.2032 -0.3048)
							(mid 0.275042 -0.275042)
							(end 0.3048 -0.2032)
						)
					)
					(width 0)
					(fill yes)
				)
			)
		)
	)
	(footprint ""
		(layer "B.Cu")
		(at 165.608 -66.7766)
		(property "Reference" "R277"
			(at 0 0 0)
			(layer "B.SilkS")
			(hide yes)
			(effects
				(font
					(size 1.27 1.27)
				)
				(justify mirror)
			)
		)
		(property "Value" "10R2F-L-GP"
			(at -0.064008 -3.993896 0)
			(unlocked yes)
			(layer "B.Fab")
			(hide yes)
			(effects
				(font
					(size 1.016 1.016)
					(thickness 0.1524)
				)
				(justify mirror)
			)
		)
		(property "Device Type" "R402H14"
			(at -0.064008 -5.517896 0)
			(unlocked yes)
			(layer "B.Fab")
			(hide yes)
			(effects
				(font
					(size 1.016 1.016)
					(thickness 0.1524)
				)
				(justify mirror)
			)
		)
		(duplicate_pad_numbers_are_jumpers no)
		(fp_line
			(start -0.508 -0.9398)
			(end 0.508 -0.9398)
			(stroke
				(width 0.1524)
				(type default)
			)
			(layer "B.SilkS")
		)
		(fp_line
			(start 0.508 -0.9398)
			(end 0.508 0.9398)
			(stroke
				(width 0.1524)
				(type default)
			)
			(layer "B.SilkS")
		)
		(fp_rect
			(start 0.508 0.9398)
			(end -0.508 -0.9398)
			(stroke
				(width 0)
				(type default)
			)
			(fill no)
			(layer "B.CrtYd")
		)
		(fp_rect
			(start 0.508 0.9398)
			(end -0.508 -0.9398)
			(stroke
				(width 0)
				(type default)
			)
			(fill no)
			(layer "B.Fab")
		)
		(pad "1" smd custom
			(at 0 -0.4445 180)
			(size 0.1397 0.1397)
			(layers "B.Cu" "B.Mask" "B.Paste")
			(net "P1V8_C")
			(options
				(clearance outline)
				(anchor circle)
			)
			(primitives
				(gr_poly
					(pts
						(arc
							(start -0.1778 0.2794)
							(mid -0.249642 0.249642)
							(end -0.2794 0.1778)
						)
						(arc
							(start -0.2794 -0.1778)
							(mid -0.249642 -0.249642)
							(end -0.1778 -0.2794)
						)
						(arc
							(start 0.1778 -0.2794)
							(mid 0.249642 -0.249642)
							(end 0.2794 -0.1778)
						)
						(arc
							(start 0.2794 0.1778)
							(mid 0.249642 0.249642)
							(end 0.1778 0.2794)
						)
					)
					(width 0)
					(fill yes)
				)
			)
		)
		(pad "2" smd custom
			(at 0 0.4445 180)
			(size 0.1397 0.1397)
			(layers "B.Cu" "B.Mask" "B.Paste")
			(net "HM40ADC_VDDA")
			(options
				(clearance outline)
				(anchor circle)
			)
			(primitives
				(gr_poly
					(pts
						(arc
							(start -0.1778 0.2794)
							(mid -0.249642 0.249642)
							(end -0.2794 0.1778)
						)
						(arc
							(start -0.2794 -0.1778)
							(mid -0.249642 -0.249642)
							(end -0.1778 -0.2794)
						)
						(arc
							(start 0.1778 -0.2794)
							(mid 0.249642 -0.249642)
							(end 0.2794 -0.1778)
						)
						(arc
							(start 0.2794 0.1778)
							(mid 0.249642 0.249642)
							(end 0.1778 0.2794)
						)
					)
					(width 0)
					(fill yes)
				)
			)
		)
	)
	(footprint ""
		(layer "B.Cu")
		(at 164.084 -47.2186)
		(property "Reference" "TP83"
			(at 0 0 0)
			(layer "B.SilkS")
			(hide yes)
			(effects
				(font
					(size 1.27 1.27)
				)
				(justify mirror)
			)
		)
		(property "Value" "TPAD28-2-GP"
			(at 0.0127 -1.6637 0)
			(unlocked yes)
			(layer "B.Fab")
			(hide yes)
			(effects
				(font
					(size 1.016 1.016)
					(thickness 0.1524)
				)
				(justify mirror)
			)
		)
		(property "Device Type" "TPAD28"
			(at 0.0127 -3.1877 0)
			(unlocked yes)
			(layer "B.Fab")
			(hide yes)
			(effects
				(font
					(size 1.016 1.016)
					(thickness 0.1524)
				)
				(justify mirror)
			)
		)
		(duplicate_pad_numbers_are_jumpers no)
		(fp_poly
			(pts
				(arc
					(start 0.3556 0)
					(mid -0.3556 0)
					(end 0.3556 0)
				)
			)
			(stroke
				(width 0)
				(type default)
			)
			(fill no)
			(layer "B.CrtYd")
		)
		(fp_poly
			(pts
				(arc
					(start 0.6096 0)
					(mid -0.6096 0)
					(end 0.6096 0)
				)
			)
			(stroke
				(width 0)
				(type default)
			)
			(fill no)
			(layer "B.Fab")
		)
		(pad "1" smd circle
			(at 0 0 180)
			(size 0.7112 0.7112)
			(layers "B.Cu" "B.Mask" "B.Paste")
			(net "SIO_DOUT_0")
		)
	)
)
